(kicad_pcb
	(version 20260206)
	(generator "pcbnew")
	(generator_version "10.0")
	(general
		(thickness 1.6)
		(legacy_teardrops no)
	)
	(paper "A4")
	(title_block
		(title "pdpb — Lightning_PDPB_BRD.brd")
		(comment 1 "Lightning (Wiwynn / Facebook NVMe JBOF) / footprints 1123-1129 of 1140")
	)
	(layers
		(0 "F.Cu" signal "TOP")
		(4 "In1.Cu" signal "L2GND")
		(6 "In2.Cu" signal "L3")
		(8 "In3.Cu" signal "L4VCC")
		(10 "In4.Cu" signal "L5VCC")
		(12 "In5.Cu" signal "L6")
		(14 "In6.Cu" signal "L7GND")
		(2 "B.Cu" signal "BOTTOM")
		(9 "F.Adhes" user "F.Adhesive")
		(11 "B.Adhes" user "B.Adhesive")
		(13 "F.Paste" user "Package Geometry/Pastemask Top")
		(15 "B.Paste" user "Package Geometry/Pastemask Bottom")
		(5 "F.SilkS" user "Ref Des/Silkscreen Top")
		(7 "B.SilkS" user "Ref Des/Silkscreen Bottom")
		(1 "F.Mask" user "Board Geometry/Soldermask Top")
		(3 "B.Mask" user "Board Geometry/Soldermask Bottom")
		(17 "Dwgs.User" user "User.Drawings")
		(19 "Cmts.User" user "User.Comments")
		(21 "Eco1.User" user "User.Eco1")
		(23 "Eco2.User" user "User.Eco2")
		(25 "Edge.Cuts" user "Board Geometry/Outline")
		(27 "Margin" user)
		(31 "F.CrtYd" user "Package Geometry/Place Bound Top")
		(29 "B.CrtYd" user "Package Geometry/Place Bound Bottom")
		(35 "F.Fab" user "Ref Des/Assembly Top")
		(33 "B.Fab" user "Ref Des/Assembly Bottom")
	)
	(footprint ""
		(layer "F.Cu")
		(at 87.503 -313.817 180)
		(property "Reference" "R9102"
			(at 0 0 180)
			(layer "F.SilkS")
			(hide yes)
			(effects
				(font
					(size 1.27 1.27)
				)
			)
		)
		(property "Value" "27R2F-GP"
			(at 0.064008 -3.993896 180)
			(unlocked yes)
			(layer "F.Fab")
			(hide yes)
			(effects
				(font
					(size 1.016 1.016)
					(thickness 0.1524)
				)
			)
		)
		(property "Device Type" "R402H16"
			(at 0.064008 -5.517896 180)
			(unlocked yes)
			(layer "F.Fab")
			(hide yes)
			(effects
				(font
					(size 1.016 1.016)
					(thickness 0.1524)
				)
			)
		)
		(duplicate_pad_numbers_are_jumpers no)
		(fp_line
			(start 0.508 -0.9398)
			(end -0.508 -0.9398)
			(stroke
				(width 0.1524)
				(type default)
			)
			(layer "F.SilkS")
		)
		(fp_line
			(start -0.508 -0.9398)
			(end -0.508 0.9398)
			(stroke
				(width 0.1524)
				(type default)
			)
			(layer "F.SilkS")
		)
		(fp_rect
			(start -0.508 0.9398)
			(end 0.508 -0.9398)
			(stroke
				(width 0)
				(type default)
			)
			(fill no)
			(layer "F.CrtYd")
		)
		(fp_rect
			(start -0.508 0.9398)
			(end 0.508 -0.9398)
			(stroke
				(width 0)
				(type default)
			)
			(fill no)
			(layer "F.Fab")
		)
		(pad "1" smd custom
			(at 0 -0.4445 180)
			(size 0.1397 0.1397)
			(layers "F.Cu" "F.Mask" "F.Paste")
			(net "PE_CLK_100M_DR11_1_R_P")
			(options
				(clearance outline)
				(anchor circle)
			)
			(primitives
				(gr_poly
					(pts
						(arc
							(start -0.1778 -0.2794)
							(mid -0.249642 -0.249642)
							(end -0.2794 -0.1778)
						)
						(arc
							(start -0.2794 0.1778)
							(mid -0.249642 0.249642)
							(end -0.1778 0.2794)
						)
						(arc
							(start 0.1778 0.2794)
							(mid 0.249642 0.249642)
							(end 0.2794 0.1778)
						)
						(arc
							(start 0.2794 -0.1778)
							(mid 0.249642 -0.249642)
							(end 0.1778 -0.2794)
						)
					)
					(width 0)
					(fill yes)
				)
			)
		)
		(pad "2" smd custom
			(at 0 0.4445 180)
			(size 0.1397 0.1397)
			(layers "F.Cu" "F.Mask" "F.Paste")
			(net "PE_CLK100M_DR11_1_P")
			(options
				(clearance outline)
				(anchor circle)
			)
			(primitives
				(gr_poly
					(pts
						(arc
							(start -0.1778 -0.2794)
							(mid -0.249642 -0.249642)
							(end -0.2794 -0.1778)
						)
						(arc
							(start -0.2794 0.1778)
							(mid -0.249642 0.249642)
							(end -0.1778 0.2794)
						)
						(arc
							(start 0.1778 0.2794)
							(mid 0.249642 0.249642)
							(end 0.2794 0.1778)
						)
						(arc
							(start 0.2794 -0.1778)
							(mid 0.249642 -0.249642)
							(end 0.1778 -0.2794)
						)
					)
					(width 0)
					(fill yes)
				)
			)
		)
	)
	(footprint ""
		(layer "F.Cu")
		(at 211.455 -44.704 180)
		(property "Reference" "R328"
			(at 0 0 180)
			(layer "F.SilkS")
			(hide yes)
			(effects
				(font
					(size 1.27 1.27)
				)
			)
		)
		(property "Value" "4K7R2F-GP"
			(at 0.064008 -3.993896 180)
			(unlocked yes)
			(layer "F.Fab")
			(hide yes)
			(effects
				(font
					(size 1.016 1.016)
					(thickness 0.1524)
				)
			)
		)
		(property "Device Type" "R402H16"
			(at 0.064008 -5.517896 180)
			(unlocked yes)
			(layer "F.Fab")
			(hide yes)
			(effects
				(font
					(size 1.016 1.016)
					(thickness 0.1524)
				)
			)
		)
		(duplicate_pad_numbers_are_jumpers no)
		(fp_line
			(start 0.508 -0.9398)
			(end -0.508 -0.9398)
			(stroke
				(width 0.1524)
				(type default)
			)
			(layer "F.SilkS")
		)
		(fp_line
			(start -0.508 -0.9398)
			(end -0.508 0.9398)
			(stroke
				(width 0.1524)
				(type default)
			)
			(layer "F.SilkS")
		)
		(fp_rect
			(start -0.508 0.9398)
			(end 0.508 -0.9398)
			(stroke
				(width 0)
				(type default)
			)
			(fill no)
			(layer "F.CrtYd")
		)
		(fp_rect
			(start -0.508 0.9398)
			(end 0.508 -0.9398)
			(stroke
				(width 0)
				(type default)
			)
			(fill no)
			(layer "F.Fab")
		)
		(pad "1" smd custom
			(at 0 -0.4445 180)
			(size 0.1397 0.1397)
			(layers "F.Cu" "F.Mask" "F.Paste")
			(net "P3V3")
			(options
				(clearance outline)
				(anchor circle)
			)
			(primitives
				(gr_poly
					(pts
						(arc
							(start -0.1778 -0.2794)
							(mid -0.249642 -0.249642)
							(end -0.2794 -0.1778)
						)
						(arc
							(start -0.2794 0.1778)
							(mid -0.249642 0.249642)
							(end -0.1778 0.2794)
						)
						(arc
							(start 0.1778 0.2794)
							(mid 0.249642 0.249642)
							(end 0.2794 0.1778)
						)
						(arc
							(start 0.2794 -0.1778)
							(mid 0.249642 -0.249642)
							(end 0.1778 -0.2794)
						)
					)
					(width 0)
					(fill yes)
				)
			)
		)
		(pad "2" smd custom
			(at 0 0.4445 180)
			(size 0.1397 0.1397)
			(layers "F.Cu" "F.Mask" "F.Paste")
			(net "I2C_B_TMP3_A2")
			(options
				(clearance outline)
				(anchor circle)
			)
			(primitives
				(gr_poly
					(pts
						(arc
							(start -0.1778 -0.2794)
							(mid -0.249642 -0.249642)
							(end -0.2794 -0.1778)
						)
						(arc
							(start -0.2794 0.1778)
							(mid -0.249642 0.249642)
							(end -0.1778 0.2794)
						)
						(arc
							(start 0.1778 0.2794)
							(mid 0.249642 0.249642)
							(end 0.2794 0.1778)
						)
						(arc
							(start 0.2794 -0.1778)
							(mid 0.249642 -0.249642)
							(end 0.1778 -0.2794)
						)
					)
					(width 0)
					(fill yes)
				)
			)
		)
	)
	(footprint ""
		(layer "F.Cu")
		(at 24.3078 -194.183 180)
		(property "Reference" "Q16"
			(at 0 0 180)
			(layer "F.SilkS")
			(hide yes)
			(effects
				(font
					(size 1.27 1.27)
				)
			)
		)
		(property "Value" "2N7002A-7-GP"
			(at 0.127 -8.9662 180)
			(unlocked yes)
			(layer "F.Fab")
			(hide yes)
			(effects
				(font
					(size 1.016 1.016)
					(thickness 0.1524)
				)
			)
		)
		(property "Device Type" "SOT23DGS2D4H48"
			(at 0.127 -10.4902 180)
			(unlocked yes)
			(layer "F.Fab")
			(hide yes)
			(effects
				(font
					(size 1.016 1.016)
					(thickness 0.1524)
				)
			)
		)
		(duplicate_pad_numbers_are_jumpers no)
		(fp_line
			(start 1.651 1.778)
			(end 1.651 -1.778)
			(stroke
				(width 0.1524)
				(type default)
			)
			(layer "F.SilkS")
		)
		(fp_line
			(start 1.651 -1.778)
			(end -1.651 -1.778)
			(stroke
				(width 0.1524)
				(type default)
			)
			(layer "F.SilkS")
		)
		(fp_line
			(start -1.651 1.778)
			(end 1.651 1.778)
			(stroke
				(width 0.1524)
				(type default)
			)
			(layer "F.SilkS")
		)
		(fp_line
			(start -1.651 -1.778)
			(end -1.651 1.778)
			(stroke
				(width 0.1524)
				(type default)
			)
			(layer "F.SilkS")
		)
		(fp_poly
			(pts
				(xy -1.778 1.8796) (xy -1.778 -1.8796) (xy 1.778 -1.8796) (xy 1.778 1.8796)
			)
			(stroke
				(width 0)
				(type default)
			)
			(fill no)
			(layer "F.CrtYd")
		)
		(fp_poly
			(pts
				(xy -1.778 1.8796) (xy -1.778 -1.8796) (xy 1.778 -1.8796) (xy 1.778 1.8796)
			)
			(stroke
				(width 0)
				(type default)
			)
			(fill no)
			(layer "F.Fab")
		)
		(pad "D" smd custom
			(at 0 -0.9525 180)
			(size 0.1905 0.1905)
			(layers "F.Cu" "F.Mask" "F.Paste")
			(net "SW_SSD8_R")
			(options
				(clearance outline)
				(anchor circle)
			)
			(primitives
				(gr_poly
					(pts
						(arc
							(start -0.1778 0.5715)
							(mid -0.321484 0.511984)
							(end -0.381 0.3683)
						)
						(arc
							(start -0.381 -0.3683)
							(mid -0.321484 -0.511984)
							(end -0.1778 -0.5715)
						)
						(arc
							(start 0.1778 -0.5715)
							(mid 0.321484 -0.511984)
							(end 0.381 -0.3683)
						)
						(arc
							(start 0.381 0.3683)
							(mid 0.321484 0.511984)
							(end 0.1778 0.5715)
						)
					)
					(width 0)
					(fill yes)
				)
			)
		)
		(pad "G" smd custom
			(at -0.98425 0.9525 180)
			(size 0.1905 0.1905)
			(layers "F.Cu" "F.Mask" "F.Paste")
			(net "SSD8_PWREN")
			(options
				(clearance outline)
				(anchor circle)
			)
			(primitives
				(gr_poly
					(pts
						(arc
							(start -0.1778 0.5715)
							(mid -0.321484 0.511984)
							(end -0.381 0.3683)
						)
						(arc
							(start -0.381 -0.3683)
							(mid -0.321484 -0.511984)
							(end -0.1778 -0.5715)
						)
						(arc
							(start 0.1778 -0.5715)
							(mid 0.321484 -0.511984)
							(end 0.381 -0.3683)
						)
						(arc
							(start 0.381 0.3683)
							(mid 0.321484 0.511984)
							(end 0.1778 0.5715)
						)
					)
					(width 0)
					(fill yes)
				)
			)
		)
		(pad "S" smd custom
			(at 0.98425 0.9525 180)
			(size 0.1905 0.1905)
			(layers "F.Cu" "F.Mask" "F.Paste")
			(net "GND")
			(options
				(clearance outline)
				(anchor circle)
			)
			(primitives
				(gr_poly
					(pts
						(arc
							(start -0.1778 0.5715)
							(mid -0.321484 0.511984)
							(end -0.381 0.3683)
						)
						(arc
							(start -0.381 -0.3683)
							(mid -0.321484 -0.511984)
							(end -0.1778 -0.5715)
						)
						(arc
							(start 0.1778 -0.5715)
							(mid 0.321484 -0.511984)
							(end 0.381 -0.3683)
						)
						(arc
							(start 0.381 0.3683)
							(mid 0.321484 0.511984)
							(end 0.1778 0.5715)
						)
					)
					(width 0)
					(fill yes)
				)
			)
		)
	)
	(footprint ""
		(layer "F.Cu")
		(at 42.203116 -343.912952 90)
		(property "Reference" "U203"
			(at 0 0 90)
			(layer "F.SilkS")
			(hide yes)
			(effects
				(font
					(size 1.27 1.27)
				)
			)
		)
		(property "Value" "SN74LVC1G08DCKR-GP"
			(at -2.3368 -8.6868 90)
			(unlocked yes)
			(layer "F.Fab")
			(hide yes)
			(effects
				(font
					(size 1.016 1.016)
					(thickness 0.1524)
				)
			)
		)
		(property "Device Type" "SC70-5H44"
			(at -2.3114 -10.414 90)
			(unlocked yes)
			(layer "F.Fab")
			(hide yes)
			(effects
				(font
					(size 1.016 1.016)
					(thickness 0.1524)
				)
			)
		)
		(duplicate_pad_numbers_are_jumpers no)
		(fp_line
			(start 1.3843 -1.8034)
			(end 1.3843 -1.1176)
			(stroke
				(width 0.3302)
				(type default)
			)
			(layer "F.SilkS")
		)
		(fp_line
			(start 0.6604 -1.8034)
			(end 1.3843 -1.8034)
			(stroke
				(width 0.3302)
				(type default)
			)
			(layer "F.SilkS")
		)
		(fp_line
			(start 1.27 -1.7018)
			(end 1.27 1.7018)
			(stroke
				(width 0.1524)
				(type default)
			)
			(layer "F.SilkS")
		)
		(fp_line
			(start -1.27 -1.7018)
			(end 1.27 -1.7018)
			(stroke
				(width 0.1524)
				(type default)
			)
			(layer "F.SilkS")
		)
		(fp_line
			(start 1.27 1.7018)
			(end -1.27 1.7018)
			(stroke
				(width 0.1524)
				(type default)
			)
			(layer "F.SilkS")
		)
		(fp_line
			(start -1.27 1.7018)
			(end -1.27 -1.7018)
			(stroke
				(width 0.1524)
				(type default)
			)
			(layer "F.SilkS")
		)
		(fp_rect
			(start -1.524 1.9558)
			(end 1.524 -1.9558)
			(stroke
				(width 0)
				(type default)
			)
			(fill no)
			(layer "F.CrtYd")
		)
		(fp_poly
			(pts
				(xy -1.524 -1.9558) (xy 1.524 -1.9558) (xy 1.524 1.9558) (xy -1.524 1.9558)
			)
			(stroke
				(width 0)
				(type default)
			)
			(fill no)
			(layer "F.Fab")
		)
		(pad "1" smd rect
			(at 0.65024 -0.8255 90)
			(size 0.4064 1.2192)
			(layers "F.Cu" "F.Mask" "F.Paste")
			(net "SSD6_CLK0_OE_MOS_N")
		)
		(pad "2" smd rect
			(at 0 -0.8255 90)
			(size 0.4064 1.2192)
			(layers "F.Cu" "F.Mask" "F.Paste")
			(net "ATTN_LED_DR6_N")
		)
		(pad "3" smd rect
			(at -0.65024 -0.8255 90)
			(size 0.4064 1.2192)
			(layers "F.Cu" "F.Mask" "F.Paste")
			(net "GND")
		)
		(pad "4" smd rect
			(at -0.65024 0.8255 90)
			(size 0.4064 1.2192)
			(layers "F.Cu" "F.Mask" "F.Paste")
			(net "ATTN_LED_DR6_AND")
		)
		(pad "5" smd rect
			(at 0.65024 0.8255 90)
			(size 0.4064 1.2192)
			(layers "F.Cu" "F.Mask" "F.Paste")
			(net "P3V3")
		)
	)
	(footprint ""
		(layer "F.Cu")
		(at 25.4 -414.7566)
		(property "Reference" "PC1181"
			(at 0 0 0)
			(layer "F.SilkS")
			(hide yes)
			(effects
				(font
					(size 1.27 1.27)
				)
			)
		)
		(property "Value" "SC22U25V6KX-GP-U"
			(at -2.860802 -5.279644 0)
			(unlocked yes)
			(layer "F.Fab")
			(hide yes)
			(effects
				(font
					(size 1.016 1.016)
					(thickness 0.1524)
				)
			)
		)
		(property "Device Type" "C1206-TO0D3H75"
			(at -2.860802 -6.803644 0)
			(unlocked yes)
			(layer "F.Fab")
			(hide yes)
			(effects
				(font
					(size 1.016 1.016)
					(thickness 0.1524)
				)
			)
		)
		(duplicate_pad_numbers_are_jumpers no)
		(fp_line
			(start -1.3081 -2.3749)
			(end 1.3081 -2.3749)
			(stroke
				(width 0.1524)
				(type default)
			)
			(layer "F.SilkS")
		)
		(fp_line
			(start -1.3081 2.3749)
			(end -1.3081 -2.3749)
			(stroke
				(width 0.1524)
				(type default)
			)
			(layer "F.SilkS")
		)
		(fp_line
			(start 1.3081 -2.3749)
			(end 1.3081 2.3749)
			(stroke
				(width 0.1524)
				(type default)
			)
			(layer "F.SilkS")
		)
		(fp_line
			(start 1.3081 2.3749)
			(end -1.3081 2.3749)
			(stroke
				(width 0.1524)
				(type default)
			)
			(layer "F.SilkS")
		)
		(fp_rect
			(start -0.8001 1.6002)
			(end 0.8001 -1.6002)
			(stroke
				(width 0)
				(type default)
			)
			(fill no)
			(layer "F.CrtYd")
		)
		(fp_poly
			(pts
				(xy -1.5621 2.4511) (xy -1.5621 1.6002) (xy 0.8001 1.6002) (xy 0.8001 -1.6002) (xy -0.8001 -1.6002)
				(xy -0.8001 1.5875) (xy -1.5621 1.5875) (xy -1.5621 -2.4511) (xy 1.5621 -2.4511) (xy 1.5621 2.4511)
			)
			(stroke
				(width 0)
				(type default)
			)
			(fill no)
			(layer "F.CrtYd")
		)
		(fp_rect
			(start -1.5621 2.4511)
			(end 1.5621 -2.4511)
			(stroke
				(width 0)
				(type default)
			)
			(fill no)
			(layer "F.Fab")
		)
		(pad "1" smd rect
			(at 0 -1.392936)
			(size 2.1082 1.4478)
			(layers "F.Cu" "F.Mask" "F.Paste")
			(net "P12V_SSD10")
		)
		(pad "2" smd rect
			(at 0 1.392936)
			(size 2.1082 1.4478)
			(layers "F.Cu" "F.Mask" "F.Paste")
			(net "GND")
		)
	)
	(footprint ""
		(layer "F.Cu")
		(at 90.043 -416.814 -90)
		(property "Reference" "R124"
			(at 0 0 270)
			(layer "F.SilkS")
			(hide yes)
			(effects
				(font
					(size 1.27 1.27)
				)
			)
		)
		(property "Value" "4K7R2J-2-GP"
			(at 0.064008 -3.993896 270)
			(unlocked yes)
			(layer "F.Fab")
			(hide yes)
			(effects
				(font
					(size 1.016 1.016)
					(thickness 0.1524)
				)
			)
		)
		(property "Device Type" "R402H16"
			(at 0.064008 -5.517896 270)
			(unlocked yes)
			(layer "F.Fab")
			(hide yes)
			(effects
				(font
					(size 1.016 1.016)
					(thickness 0.1524)
				)
			)
		)
		(duplicate_pad_numbers_are_jumpers no)
		(fp_line
			(start -0.508 -0.9398)
			(end -0.508 0.9398)
			(stroke
				(width 0.1524)
				(type default)
			)
			(layer "F.SilkS")
		)
		(fp_line
			(start 0.508 -0.9398)
			(end -0.508 -0.9398)
			(stroke
				(width 0.1524)
				(type default)
			)
			(layer "F.SilkS")
		)
		(fp_rect
			(start -0.508 0.9398)
			(end 0.508 -0.9398)
			(stroke
				(width 0)
				(type default)
			)
			(fill no)
			(layer "F.CrtYd")
		)
		(fp_rect
			(start -0.508 0.9398)
			(end 0.508 -0.9398)
			(stroke
				(width 0)
				(type default)
			)
			(fill no)
			(layer "F.Fab")
		)
		(pad "1" smd custom
			(at 0 -0.4445 270)
			(size 0.1397 0.1397)
			(layers "F.Cu" "F.Mask" "F.Paste")
			(net "P3V3")
			(options
				(clearance outline)
				(anchor circle)
			)
			(primitives
				(gr_poly
					(pts
						(arc
							(start -0.1778 -0.2794)
							(mid -0.249642 -0.249642)
							(end -0.2794 -0.1778)
						)
						(arc
							(start -0.2794 0.1778)
							(mid -0.249642 0.249642)
							(end -0.1778 0.2794)
						)
						(arc
							(start 0.1778 0.2794)
							(mid 0.249642 0.249642)
							(end 0.2794 0.1778)
						)
						(arc
							(start 0.2794 -0.1778)
							(mid 0.249642 -0.249642)
							(end 0.1778 -0.2794)
						)
					)
					(width 0)
					(fill yes)
				)
			)
		)
		(pad "2" smd custom
			(at 0 0.4445 270)
			(size 0.1397 0.1397)
			(layers "F.Cu" "F.Mask" "F.Paste")
			(net "SSD10_CLK0_OE_N")
			(options
				(clearance outline)
				(anchor circle)
			)
			(primitives
				(gr_poly
					(pts
						(arc
							(start -0.1778 -0.2794)
							(mid -0.249642 -0.249642)
							(end -0.2794 -0.1778)
						)
						(arc
							(start -0.2794 0.1778)
							(mid -0.249642 0.249642)
							(end -0.1778 0.2794)
						)
						(arc
							(start 0.1778 0.2794)
							(mid 0.249642 0.249642)
							(end 0.2794 0.1778)
						)
						(arc
							(start 0.2794 -0.1778)
							(mid 0.249642 -0.249642)
							(end 0.1778 -0.2794)
						)
					)
					(width 0)
					(fill yes)
				)
			)
		)
	)
	(footprint ""
		(layer "F.Cu")
		(at 21.30425 -401.79625)
		(property "Reference" "R9766"
			(at 0 0 0)
			(layer "F.SilkS")
			(hide yes)
			(effects
				(font
					(size 1.27 1.27)
				)
			)
		)
		(property "Value" "4K7R2J-2-GP"
			(at 0.064008 -3.993896 0)
			(unlocked yes)
			(layer "F.Fab")
			(hide yes)
			(effects
				(font
					(size 1.016 1.016)
					(thickness 0.1524)
				)
			)
		)
		(property "Device Type" "R402H16"
			(at 0.064008 -5.517896 0)
			(unlocked yes)
			(layer "F.Fab")
			(hide yes)
			(effects
				(font
					(size 1.016 1.016)
					(thickness 0.1524)
				)
			)
		)
		(duplicate_pad_numbers_are_jumpers no)
		(fp_line
			(start -0.508 -0.9398)
			(end -0.508 0.9398)
			(stroke
				(width 0.1524)
				(type default)
			)
			(layer "F.SilkS")
		)
		(fp_line
			(start 0.508 -0.9398)
			(end -0.508 -0.9398)
			(stroke
				(width 0.1524)
				(type default)
			)
			(layer "F.SilkS")
		)
		(fp_rect
			(start -0.508 0.9398)
			(end 0.508 -0.9398)
			(stroke
				(width 0)
				(type default)
			)
			(fill no)
			(layer "F.CrtYd")
		)
		(fp_rect
			(start -0.508 0.9398)
			(end 0.508 -0.9398)
			(stroke
				(width 0)
				(type default)
			)
			(fill no)
			(layer "F.Fab")
		)
		(pad "1" smd custom
			(at 0 -0.4445)
			(size 0.1397 0.1397)
			(layers "F.Cu" "F.Mask" "F.Paste")
			(net "SSD6_PWREN")
			(options
				(clearance outline)
				(anchor circle)
			)
			(primitives
				(gr_poly
					(pts
						(arc
							(start -0.1778 -0.2794)
							(mid -0.249642 -0.249642)
							(end -0.2794 -0.1778)
						)
						(arc
							(start -0.2794 0.1778)
							(mid -0.249642 0.249642)
							(end -0.1778 0.2794)
						)
						(arc
							(start 0.1778 0.2794)
							(mid 0.249642 0.249642)
							(end 0.2794 0.1778)
						)
						(arc
							(start 0.2794 -0.1778)
							(mid 0.249642 -0.249642)
							(end 0.1778 -0.2794)
						)
					)
					(width 0)
					(fill yes)
				)
			)
		)
		(pad "2" smd custom
			(at 0 0.4445)
			(size 0.1397 0.1397)
			(layers "F.Cu" "F.Mask" "F.Paste")
			(net "GND")
			(options
				(clearance outline)
				(anchor circle)
			)
			(primitives
				(gr_poly
					(pts
						(arc
							(start -0.1778 -0.2794)
							(mid -0.249642 -0.249642)
							(end -0.2794 -0.1778)
						)
						(arc
							(start -0.2794 0.1778)
							(mid -0.249642 0.249642)
							(end -0.1778 0.2794)
						)
						(arc
							(start 0.1778 0.2794)
							(mid 0.249642 0.249642)
							(end 0.2794 0.1778)
						)
						(arc
							(start 0.2794 -0.1778)
							(mid 0.249642 -0.249642)
							(end 0.1778 -0.2794)
						)
					)
					(width 0)
					(fill yes)
				)
			)
		)
	)
)
